# S9S_MB_2U (Grand Teton) — schematic netlist excerpt (pin names and nets, part order shuffled) for the footprints in the layout excerpt that follows; sources: Cadence DE-HDL packaged netlist, KiCad conversion of 03242023_DA0F0TMBIJ0_F0T_Motherboard_J_brd_V01_OCP.brd

J45  CONN60_101062636003K02LF  CONN60_10106263-6003K02LF IO  pkg HSD_M60D4H2D_P2-54W2-54_LDHXB  page 245
  A1  = TP_J45_A1
  A2  = FM_AC_PWR_BTN_PDB_N
  A3  = P3V3_PDB_AUX_ADC
  B1  = RST_SMB_SWITCH_R_N
  B2  = PWRGD_P3V3_AUX_PDB_BUF
  B3  = GND
  C1  = SMB_FAN_3V3AUX_BUF_R_SCL
  C2  = SMB_FAN_3V3AUX_BUF_R_SDA
  C3  = HPDB_HSC_PWRGD_R
  D1  = FM_FAN_PWR_EN_R
  D2  = FM_GPU_HSC_EN_BUF_R1
  D3  = PDB_PRSNT_N
  P1_1  = GND
  P1_2  = GND
  P1_3  = GND
  P1_4  = GND
  P1_5  = GND
  P1_6  = GND
  P1_7  = GND
  P1_8  = GND
  P2_1  = GND
  P2_2  = GND
  P2_3  = GND
  P2_4  = GND
  P2_5  = GND
  P2_6  = GND
  P2_7  = GND
  P2_8  = GND
  P3_1  = GND
  P3_2  = GND
  P3_3  = GND
  P3_4  = GND
  P3_5  = GND
  P3_6  = GND
  P3_7  = GND
  P3_8  = GND
  P4_1  = P12V_PSU
  P4_2  = P12V_PSU
  P4_3  = P12V_PSU
  P4_4  = P12V_PSU
  P4_5  = P12V_PSU
  P4_6  = P12V_PSU
  P4_7  = P12V_PSU
  P4_8  = P12V_PSU
  P5_1  = P12V_PSU
  P5_2  = P12V_PSU
  P5_3  = P12V_PSU
  P5_4  = P12V_PSU
  P5_5  = P12V_PSU
  P5_6  = P12V_PSU
  P5_7  = P12V_PSU
  P5_8  = P12V_PSU
  P6_1  = P12V_PSU
  P6_2  = P12V_PSU
  P6_3  = P12V_PSU
  P6_4  = P12V_PSU
  P6_5  = P12V_PSU
  P6_6  = P12V_PSU
  P6_7  = P12V_PSU
  P6_8  = P12V_PSU

(kicad_pcb
	(version 20260206)
	(generator "pcbnew")
	(generator_version "10.0")
	(general
		(thickness 1.6)
		(legacy_teardrops no)
	)
	(paper "A4")
	(title_block
		(title "03242023_DA0F0TMBIJ0_F0T_Motherboard_J_brd_V01_OCP.brd")
		(comment 1 "Grand Teton / footprint 2359 of 6105 (J45), pads 1-35 of 62")
	)
	(layers
		(0 "F.Cu" signal "TOP")
		(4 "In1.Cu" signal "GND")
		(6 "In2.Cu" signal "IN1")
		(8 "In3.Cu" signal "GND1")
		(10 "In4.Cu" signal "IN2")
		(12 "In5.Cu" signal "GND2")
		(14 "In6.Cu" signal "IN3")
		(16 "In7.Cu" signal "GND3")
		(18 "In8.Cu" signal "VCC")
		(20 "In9.Cu" signal "VCC1")
		(22 "In10.Cu" signal "GND4")
		(24 "In11.Cu" signal "IN4")
		(26 "In12.Cu" signal "GND5")
		(28 "In13.Cu" signal "IN5")
		(30 "In14.Cu" signal "GND6")
		(32 "In15.Cu" signal "IN6")
		(34 "In16.Cu" signal "GND7")
		(2 "B.Cu" signal "BOTTOM")
		(9 "F.Adhes" user "F.Adhesive")
		(11 "B.Adhes" user "B.Adhesive")
		(13 "F.Paste" user "Package Geometry/Pastemask Top")
		(15 "B.Paste" user "Package Geometry/Pastemask Bottom")
		(5 "F.SilkS" user "Ref Des/Silkscreen Top")
		(7 "B.SilkS" user "Ref Des/Silkscreen Bottom")
		(1 "F.Mask" user "Board Geometry/Soldermask Top")
		(3 "B.Mask" user "Board Geometry/Soldermask Bottom")
		(17 "Dwgs.User" user "User.Drawings")
		(19 "Cmts.User" user "User.Comments")
		(21 "Eco1.User" user "User.Eco1")
		(23 "Eco2.User" user "User.Eco2")
		(25 "Edge.Cuts" user "Board Geometry/Outline")
		(27 "Margin" user)
		(31 "F.CrtYd" user "Package Geometry/Place Bound Top")
		(29 "B.CrtYd" user "Package Geometry/Place Bound Bottom")
		(35 "F.Fab" user "Ref Des/Assembly Top")
		(33 "B.Fab" user "Ref Des/Assembly Bottom")
	)
	(footprint ""
		(layer "F.Cu")
		(at 238.45012 -435.58206 -90)
		(property "Reference" "J45"
			(at 7.573772 -37.93236 0)
			(unlocked yes)
			(layer "F.SilkS")
			(effects
				(font
					(size 0.7874 0.5842)
					(thickness 0.1524)
				)
				(justify left)
			)
		)
		(property "Value" ""
			(at 0 0 270)
			(layer "F.Fab")
			(effects
				(font
					(size 1.27 1.27)
				)
			)
		)
		(duplicate_pad_numbers_are_jumpers no)
		(pad "" np_thru_hole circle
			(at 2.54 -32.385 270)
			(size 0 0)
			(drill 3.048)
			(layers "*.Cu" "*.Mask")
			(clearance 0)
		)
		(pad "" np_thru_hole circle
			(at 2.54 37.465 270)
			(size 0 0)
			(drill 3.048)
			(layers "*.Cu" "*.Mask")
			(clearance 0)
		)
		(pad "A1" thru_hole rect
			(at 0 0 270)
			(size 1.669796 1.669796)
			(drill 1.01981)
			(layers "*.Cu" "*.Mask")
			(remove_unused_layers no)
			(net "TP_J45_A1")
			(clearance -0.070866)
			(padstack
				(mode front_inner_back)
				(layer "Inner"
					(shape circle)
					(size 1.669796 1.669796)
					(clearance -0.070866)
				)
				(layer "B.Cu"
					(shape rect)
					(size 1.669796 1.669796)
					(clearance -0.070866)
				)
			)
		)
		(pad "A2" thru_hole circle
			(at 0 2.54 270)
			(size 1.669796 1.669796)
			(drill 1.01981)
			(layers "*.Cu" "*.Mask")
			(remove_unused_layers no)
			(net "FM_AC_PWR_BTN_PDB_N")
			(clearance -0.070866)
		)
		(pad "A3" thru_hole circle
			(at 0 5.08 270)
			(size 1.669796 1.669796)
			(drill 1.01981)
			(layers "*.Cu" "*.Mask")
			(remove_unused_layers no)
			(net "P3V3_PDB_AUX_ADC")
			(clearance -0.070866)
		)
		(pad "B1" thru_hole circle
			(at 2.54 0 270)
			(size 1.669796 1.669796)
			(drill 1.01981)
			(layers "*.Cu" "*.Mask")
			(remove_unused_layers no)
			(net "RST_SMB_SWITCH_R_N")
			(clearance -0.070866)
		)
		(pad "B2" thru_hole circle
			(at 2.54 2.54 270)
			(size 1.669796 1.669796)
			(drill 1.01981)
			(layers "*.Cu" "*.Mask")
			(remove_unused_layers no)
			(net "PWRGD_P3V3_AUX_PDB_BUF")
			(clearance -0.070866)
		)
		(pad "B3" thru_hole circle
			(at 2.54 5.08 270)
			(size 1.669796 1.669796)
			(drill 1.01981)
			(layers "*.Cu" "*.Mask")
			(remove_unused_layers no)
			(net "GND")
			(clearance -0.070866)
		)
		(pad "C1" thru_hole circle
			(at 5.08 0 270)
			(size 1.669796 1.669796)
			(drill 1.01981)
			(layers "*.Cu" "*.Mask")
			(remove_unused_layers no)
			(net "SMB_FAN_3V3AUX_BUF_R_SCL")
			(clearance -0.070866)
		)
		(pad "C2" thru_hole circle
			(at 5.08 2.54 270)
			(size 1.669796 1.669796)
			(drill 1.01981)
			(layers "*.Cu" "*.Mask")
			(remove_unused_layers no)
			(net "SMB_FAN_3V3AUX_BUF_R_SDA")
			(clearance -0.070866)
		)
		(pad "C3" thru_hole circle
			(at 5.08 5.08 270)
			(size 1.669796 1.669796)
			(drill 1.01981)
			(layers "*.Cu" "*.Mask")
			(remove_unused_layers no)
			(net "HPDB_HSC_PWRGD_R")
			(clearance -0.070866)
		)
		(pad "D1" thru_hole circle
			(at 7.62 0 270)
			(size 1.669796 1.669796)
			(drill 1.01981)
			(layers "*.Cu" "*.Mask")
			(remove_unused_layers no)
			(net "FM_FAN_PWR_EN_R")
			(clearance -0.070866)
		)
		(pad "D2" thru_hole circle
			(at 7.62 2.54 270)
			(size 1.669796 1.669796)
			(drill 1.01981)
			(layers "*.Cu" "*.Mask")
			(remove_unused_layers no)
			(net "FM_GPU_HSC_EN_BUF_R1")
			(clearance -0.070866)
		)
		(pad "D3" thru_hole circle
			(at 7.62 5.08 270)
			(size 1.669796 1.669796)
			(drill 1.01981)
			(layers "*.Cu" "*.Mask")
			(remove_unused_layers no)
			(net "PDB_PRSNT_N")
			(clearance -0.070866)
		)
		(pad "P1_1" thru_hole circle
			(at 0 -25.4 270)
			(size 1.669796 1.669796)
			(drill 1.01981)
			(layers "*.Cu" "*.Mask")
			(remove_unused_layers no)
			(net "GND")
			(clearance -0.070866)
		)
		(pad "P1_2" thru_hole circle
			(at 2.54 -25.4 270)
			(size 1.669796 1.669796)
			(drill 1.01981)
			(layers "*.Cu" "*.Mask")
			(remove_unused_layers no)
			(net "GND")
			(clearance -0.070866)
		)
		(pad "P1_3" thru_hole circle
			(at 5.08 -25.4 270)
			(size 1.669796 1.669796)
			(drill 1.01981)
			(layers "*.Cu" "*.Mask")
			(remove_unused_layers no)
			(net "GND")
			(clearance -0.070866)
		)
		(pad "P1_4" thru_hole circle
			(at 7.62 -25.4 270)
			(size 1.669796 1.669796)
			(drill 1.01981)
			(layers "*.Cu" "*.Mask")
			(remove_unused_layers no)
			(net "GND")
			(clearance -0.070866)
		)
		(pad "P1_5" thru_hole circle
			(at 0 -22.86 270)
			(size 1.669796 1.669796)
			(drill 1.01981)
			(layers "*.Cu" "*.Mask")
			(remove_unused_layers no)
			(net "GND")
			(clearance -0.070866)
		)
		(pad "P1_6" thru_hole circle
			(at 2.54 -22.86 270)
			(size 1.669796 1.669796)
			(drill 1.01981)
			(layers "*.Cu" "*.Mask")
			(remove_unused_layers no)
			(net "GND")
			(clearance -0.070866)
		)
		(pad "P1_7" thru_hole circle
			(at 5.08 -22.86 270)
			(size 1.669796 1.669796)
			(drill 1.01981)
			(layers "*.Cu" "*.Mask")
			(remove_unused_layers no)
			(net "GND")
			(clearance -0.070866)
		)
		(pad "P1_8" thru_hole circle
			(at 7.62 -22.86 270)
			(size 1.669796 1.669796)
			(drill 1.01981)
			(layers "*.Cu" "*.Mask")
			(remove_unused_layers no)
			(net "GND")
			(clearance -0.070866)
		)
		(pad "P2_1" thru_hole circle
			(at 0 -16.51 270)
			(size 1.669796 1.669796)
			(drill 1.01981)
			(layers "*.Cu" "*.Mask")
			(remove_unused_layers no)
			(net "GND")
			(clearance -0.070866)
		)
		(pad "P2_2" thru_hole circle
			(at 2.54 -16.51 270)
			(size 1.669796 1.669796)
			(drill 1.01981)
			(layers "*.Cu" "*.Mask")
			(remove_unused_layers no)
			(net "GND")
			(clearance -0.070866)
		)
		(pad "P2_3" thru_hole circle
			(at 5.08 -16.51 270)
			(size 1.669796 1.669796)
			(drill 1.01981)
			(layers "*.Cu" "*.Mask")
			(remove_unused_layers no)
			(net "GND")
			(clearance -0.070866)
		)
		(pad "P2_4" thru_hole circle
			(at 7.62 -16.51 270)
			(size 1.669796 1.669796)
			(drill 1.01981)
			(layers "*.Cu" "*.Mask")
			(remove_unused_layers no)
			(net "GND")
			(clearance -0.070866)
		)
		(pad "P2_5" thru_hole circle
			(at 0 -13.97 270)
			(size 1.669796 1.669796)
			(drill 1.01981)
			(layers "*.Cu" "*.Mask")
			(remove_unused_layers no)
			(net "GND")
			(clearance -0.070866)
		)
		(pad "P2_6" thru_hole circle
			(at 2.54 -13.97 270)
			(size 1.669796 1.669796)
			(drill 1.01981)
			(layers "*.Cu" "*.Mask")
			(remove_unused_layers no)
			(net "GND")
			(clearance -0.070866)
		)
		(pad "P2_7" thru_hole circle
			(at 5.08 -13.97 270)
			(size 1.669796 1.669796)
			(drill 1.01981)
			(layers "*.Cu" "*.Mask")
			(remove_unused_layers no)
			(net "GND")
			(clearance -0.070866)
		)
		(pad "P2_8" thru_hole circle
			(at 7.62 -13.97 270)
			(size 1.669796 1.669796)
			(drill 1.01981)
			(layers "*.Cu" "*.Mask")
			(remove_unused_layers no)
			(net "GND")
			(clearance -0.070866)
		)
		(pad "P3_1" thru_hole circle
			(at 0 -7.62 270)
			(size 1.669796 1.669796)
			(drill 1.01981)
			(layers "*.Cu" "*.Mask")
			(remove_unused_layers no)
			(net "GND")
			(clearance -0.070866)
		)
		(pad "P3_2" thru_hole circle
			(at 2.54 -7.62 270)
			(size 1.669796 1.669796)
			(drill 1.01981)
			(layers "*.Cu" "*.Mask")
			(remove_unused_layers no)
			(net "GND")
			(clearance -0.070866)
		)
		(pad "P3_3" thru_hole circle
			(at 5.08 -7.62 270)
			(size 1.669796 1.669796)
			(drill 1.01981)
			(layers "*.Cu" "*.Mask")
			(remove_unused_layers no)
			(net "GND")
			(clearance -0.070866)
		)
		(pad "P3_4" thru_hole circle
			(at 7.62 -7.62 270)
			(size 1.669796 1.669796)
			(drill 1.01981)
			(layers "*.Cu" "*.Mask")
			(remove_unused_layers no)
			(net "GND")
			(clearance -0.070866)
		)
		(pad "P3_5" thru_hole circle
			(at 0 -5.08 270)
			(size 1.669796 1.669796)
			(drill 1.01981)
			(layers "*.Cu" "*.Mask")
			(remove_unused_layers no)
			(net "GND")
			(clearance -0.070866)
		)
	)
)
